# T6G (Grand Teton) — schematic netlist excerpt (pin names and nets, part order shuffled) for the footprints in the layout excerpt that follows; sources: Cadence DE-HDL packaged netlist, KiCad conversion of 04192023_DAF0TMB3IC0_F0TG_MB_C_brd_V02_OCP.brd

PU18  ISL99390FRZTR5935  ISL99390FRZ-TR5935 IC  pkg QFN21_6X5XB  page 205
  VOS  = PVDDIO_P0_VOS2
  AGND  = GND
  VCC  = PVDDIO_P0_VCC2
  PVCC  = PVDDCR_CPU1_P0_PVCC
  PGND1  = GND
  GL1  = NC_PVDDIO_P0_GL1_2
  PGND2  = GND
  SW  = SW_PVDDIO_P0_SW2
  VIN1  = SW_P12V_AUX_PVDDIO_P0_FLT
  VIN2  = SW_P12V_AUX_PVDDIO_P0_FLT
  DNC  = NC_PVDDIO_P0_DNC2
  PHASE  = SW_PVDDIO_P0_BOOTR2
  BOOT  = SW_PVDDIO_P0_BOOT2
  PWM  = PVDDIO_P0_PWM2
  EN  = PVDDIO_P0_VCC2
  TOUT_FLT  = PVDDIO_P0_TEMP1
  LSET  = PVDDIO_P0_LSET2
  IOUT  = PVDDIO_P0_IMON2
  REFIN  = PVDDCR_CPU1_P0_VCCS
  PGND3  = GND
  GL2  = NC_PVDDIO_P0_GL2_2

(kicad_pcb
	(version 20260206)
	(generator "pcbnew")
	(generator_version "10.0")
	(general
		(thickness 1.6)
		(legacy_teardrops no)
	)
	(paper "A4")
	(title_block
		(title "04192023_DAF0TMB3IC0_F0TG_MB_C_brd_V02_OCP.brd")
		(comment 1 "Grand Teton / footprints 2856-2856 of 8354")
	)
	(layers
		(0 "F.Cu" signal "TOP")
		(4 "In1.Cu" signal "GND")
		(6 "In2.Cu" signal "IN1")
		(8 "In3.Cu" signal "GND1")
		(10 "In4.Cu" signal "IN2")
		(12 "In5.Cu" signal "GND2")
		(14 "In6.Cu" signal "IN3")
		(16 "In7.Cu" signal "GND3")
		(18 "In8.Cu" signal "VCC")
		(20 "In9.Cu" signal "VCC1")
		(22 "In10.Cu" signal "GND4")
		(24 "In11.Cu" signal "IN4")
		(26 "In12.Cu" signal "GND5")
		(28 "In13.Cu" signal "IN5")
		(30 "In14.Cu" signal "GND6")
		(32 "In15.Cu" signal "IN6")
		(34 "In16.Cu" signal "GND7")
		(2 "B.Cu" signal "BOTTOM")
		(9 "F.Adhes" user "F.Adhesive")
		(11 "B.Adhes" user "B.Adhesive")
		(13 "F.Paste" user "Package Geometry/Pastemask Top")
		(15 "B.Paste" user "Package Geometry/Pastemask Bottom")
		(5 "F.SilkS" user "Ref Des/Silkscreen Top")
		(7 "B.SilkS" user "Ref Des/Silkscreen Bottom")
		(1 "F.Mask" user "Board Geometry/Soldermask Top")
		(3 "B.Mask" user "Board Geometry/Soldermask Bottom")
		(17 "Dwgs.User" user "User.Drawings")
		(19 "Cmts.User" user "User.Comments")
		(21 "Eco1.User" user "User.Eco1")
		(23 "Eco2.User" user "User.Eco2")
		(25 "Edge.Cuts" user "Board Geometry/Outline")
		(27 "Margin" user)
		(31 "F.CrtYd" user "Package Geometry/Place Bound Top")
		(29 "B.CrtYd" user "Package Geometry/Place Bound Bottom")
		(35 "F.Fab" user "Ref Des/Assembly Top")
		(33 "B.Fab" user "Ref Des/Assembly Bottom")
	)
	(footprint ""
		(layer "F.Cu")
		(at 292.008306 -346.71635)
		(property "Reference" "PU18"
			(at -2.321306 -7.71398 0)
			(unlocked yes)
			(layer "F.SilkS")
			(effects
				(font
					(size 0.7874 0.5842)
					(thickness 0.1524)
				)
				(justify left)
			)
		)
		(property "Value" ""
			(at 0 0 0)
			(layer "F.Fab")
			(effects
				(font
					(size 1.27 1.27)
				)
			)
		)
		(duplicate_pad_numbers_are_jumpers no)
		(fp_line
			(start -2.500122 -2.999994)
			(end -2.24409 -2.999994)
			(stroke
				(width 0.1524)
				(type default)
			)
			(layer "F.SilkS")
		)
		(fp_line
			(start -2.500122 -2.529078)
			(end -2.500122 -2.999994)
			(stroke
				(width 0.1524)
				(type default)
			)
			(layer "F.SilkS")
		)
		(fp_line
			(start -2.500122 0.6604)
			(end -2.500122 0.229108)
			(stroke
				(width 0.1524)
				(type default)
			)
			(layer "F.SilkS")
		)
		(fp_line
			(start -2.500122 2.999994)
			(end -2.500122 2.339594)
			(stroke
				(width 0.1524)
				(type default)
			)
			(layer "F.SilkS")
		)
		(fp_line
			(start -2.2987 2.999994)
			(end -2.500122 2.999994)
			(stroke
				(width 0.1524)
				(type default)
			)
			(layer "F.SilkS")
		)
		(fp_line
			(start 2.31394 -2.999994)
			(end 2.500122 -2.999994)
			(stroke
				(width 0.1524)
				(type default)
			)
			(layer "F.SilkS")
		)
		(fp_line
			(start 2.500122 -2.999994)
			(end 2.500122 -2.44348)
			(stroke
				(width 0.1524)
				(type default)
			)
			(layer "F.SilkS")
		)
		(fp_line
			(start 2.500122 2.339594)
			(end 2.500122 2.999994)
			(stroke
				(width 0.1524)
				(type default)
			)
			(layer "F.SilkS")
		)
		(fp_line
			(start 2.500122 2.999994)
			(end 2.2987 2.999994)
			(stroke
				(width 0.1524)
				(type default)
			)
			(layer "F.SilkS")
		)
		(fp_poly
			(pts
				(xy -3.429508 -2.672588) (xy -2.96545 -3.136646) (xy -2.733548 -2.440686)
			)
			(stroke
				(width 0)
				(type default)
			)
			(fill yes)
			(layer "F.SilkS")
		)
		(fp_line
			(start -2.500122 -2.999994)
			(end 2.500122 -2.999994)
			(stroke
				(width 0.1)
				(type default)
			)
			(layer "F.Fab")
		)
		(fp_line
			(start -2.500122 2.999994)
			(end -2.500122 -2.999994)
			(stroke
				(width 0.1)
				(type default)
			)
			(layer "F.Fab")
		)
		(fp_line
			(start 2.500122 -2.999994)
			(end 2.500122 2.999994)
			(stroke
				(width 0.1)
				(type default)
			)
			(layer "F.Fab")
		)
		(fp_line
			(start 2.500122 2.999994)
			(end -2.500122 2.999994)
			(stroke
				(width 0.1)
				(type default)
			)
			(layer "F.Fab")
		)
		(fp_poly
			(pts
				(xy -4.218432 -2.783078) (xy -4.218432 -1.767078) (xy -3.202432 -2.275078)
			)
			(stroke
				(width 0)
				(type default)
			)
			(fill yes)
			(layer "F.Fab")
		)
		(pad "1" smd rect
			(at -2.400046 -2.275078 90)
			(size 0.2286 0.6096)
			(layers "F.Cu" "F.Mask" "F.Paste")
			(net "PVDDIO_P0_VOS2")
		)
		(pad "2" smd rect
			(at -2.400046 -1.82499 90)
			(size 0.2286 0.6096)
			(layers "F.Cu" "F.Mask" "F.Paste")
			(net "GND")
		)
		(pad "3" smd rect
			(at -2.400046 -1.374902 90)
			(size 0.2286 0.6096)
			(layers "F.Cu" "F.Mask" "F.Paste")
			(net "PVDDIO_P0_VCC2")
		)
		(pad "4" smd rect
			(at -2.400046 -0.925068 90)
			(size 0.2286 0.6096)
			(layers "F.Cu" "F.Mask" "F.Paste")
			(net "PVDDCR_CPU1_P0_PVCC")
		)
		(pad "5" smd rect
			(at -2.400046 -0.47498 90)
			(size 0.2286 0.6096)
			(layers "F.Cu" "F.Mask" "F.Paste")
			(net "GND")
		)
		(pad "6" smd rect
			(at -2.400046 -0.024892 90)
			(size 0.2286 0.6096)
			(layers "F.Cu" "F.Mask" "F.Paste")
			(net "NC_PVDDIO_P0_GL1_2")
		)
		(pad "7_9-20_24" smd circle
			(at 0 1.150112 90)
			(size 0 0)
			(layers "F.Cu" "F.Mask" "F.Paste")
			(net "GND")
		)
		(pad "10_19" smd rect
			(at 0 2.899918 90)
			(size 0.6096 4.318)
			(layers "F.Cu" "F.Mask" "F.Paste")
			(net "SW_PVDDIO_P0_SW2")
		)
		(pad "25_29" smd rect
			(at 1.549908 -1.279906 270)
			(size 2.0574 2.3114)
			(layers "F.Cu" "F.Mask" "F.Paste")
			(net "SW_P12V_AUX_PVDDIO_P0_FLT")
		)
		(pad "30" smd rect
			(at 2.05994 -2.899918)
			(size 0.2286 0.6096)
			(layers "F.Cu" "F.Mask" "F.Paste")
			(net "SW_P12V_AUX_PVDDIO_P0_FLT")
		)
		(pad "31" smd rect
			(at 1.610106 -2.899918)
			(size 0.2286 0.6096)
			(layers "F.Cu" "F.Mask" "F.Paste")
			(net "NC_PVDDIO_P0_DNC2")
		)
		(pad "32" smd rect
			(at 1.160018 -2.899918)
			(size 0.2286 0.6096)
			(layers "F.Cu" "F.Mask" "F.Paste")
			(net "SW_PVDDIO_P0_BOOTR2")
		)
		(pad "33" smd rect
			(at 0.70993 -2.899918)
			(size 0.2286 0.6096)
			(layers "F.Cu" "F.Mask" "F.Paste")
			(net "SW_PVDDIO_P0_BOOT2")
		)
		(pad "34" smd rect
			(at 0.260096 -2.899918)
			(size 0.2286 0.6096)
			(layers "F.Cu" "F.Mask" "F.Paste")
			(net "PVDDIO_P0_PWM2")
		)
		(pad "35" smd rect
			(at -0.189992 -2.899918)
			(size 0.2286 0.6096)
			(layers "F.Cu" "F.Mask" "F.Paste")
			(net "PVDDIO_P0_VCC2")
		)
		(pad "36" smd rect
			(at -0.64008 -2.899918)
			(size 0.2286 0.6096)
			(layers "F.Cu" "F.Mask" "F.Paste")
			(net "PVDDIO_P0_TEMP1")
		)
		(pad "37" smd rect
			(at -1.089914 -2.899918)
			(size 0.2286 0.6096)
			(layers "F.Cu" "F.Mask" "F.Paste")
			(net "PVDDIO_P0_LSET2")
		)
		(pad "38" smd rect
			(at -1.540002 -2.899918)
			(size 0.2286 0.6096)
			(layers "F.Cu" "F.Mask" "F.Paste")
			(net "PVDDIO_P0_IMON2")
		)
		(pad "39" smd rect
			(at -1.99009 -2.899918)
			(size 0.2286 0.6096)
			(layers "F.Cu" "F.Mask" "F.Paste")
			(net "PVDDCR_CPU1_P0_VCCS")
		)
		(pad "40" smd rect
			(at -0.87503 -1.27508)
			(size 1.7526 1.9558)
			(layers "F.Cu" "F.Mask" "F.Paste")
			(net "GND")
		)
		(pad "41" smd rect
			(at -1.525016 0.249936 270)
			(size 0.3048 0.4572)
			(layers "F.Cu" "F.Mask" "F.Paste")
			(net "NC_PVDDIO_P0_GL2_2")
		)
		(zone
			(layer "F.Cu")
			(hatch none 0.5)
			(connect_pads
				(clearance 0)
			)
			(min_thickness 0.25)
			(keepout
				(tracks not_allowed)
				(vias allowed)
				(pads allowed)
				(copperpour not_allowed)
				(footprints allowed)
			)
			(placement
				(enabled no)
				(sheetname "")
			)
			(fill
				(thermal_gap 0.5)
				(thermal_bridge_width 0.5)
				(island_removal_mode 0)
			)
			(polygon
				(pts
					(xy 289.508184 -344.150442) (xy 289.508184 -344.465656) (xy 294.508428 -344.465656) (xy 294.508428 -344.142568)
					(xy 294.218106 -344.142568) (xy 294.218106 -344.172032) (xy 289.798506 -344.172032) (xy 289.798506 -344.150442)
				)
			)
		)
		(zone
			(layer "F.Cu")
			(hatch none 0.5)
			(connect_pads
				(clearance 0)
			)
			(min_thickness 0.25)
			(keepout
				(tracks not_allowed)
				(vias allowed)
				(pads allowed)
				(copperpour not_allowed)
				(footprints allowed)
			)
			(placement
				(enabled no)
				(sheetname "")
			)
			(fill
				(thermal_gap 0.5)
				(thermal_bridge_width 0.5)
				(island_removal_mode 0)
			)
			(polygon
				(pts
					(xy 292.060376 -346.96273) (xy 292.060376 -349.02013) (xy 290.206176 -349.02013) (xy 290.206176 -348.779084)
					(xy 289.96386 -348.779084) (xy 289.96386 -349.260668) (xy 293.766494 -349.260668) (xy 293.766494 -349.075756)
					(xy 292.351714 -349.075756) (xy 292.351714 -346.916756) (xy 294.508428 -346.916756) (xy 294.508428 -346.667074)
					(xy 292.356032 -346.667074)
				)
			)
		)
	)
)
